(kicad_pcb
	(version 20260206)
	(generator "pcbnew")
	(generator_version "10.0")
	(general
		(thickness 1.6)
		(legacy_teardrops no)
	)
	(paper "A4")
	(title_block
		(title "Wiwynn_Tioga_Pass_MB.brd")
		(comment 1 "Tioga Pass / footprint 190 of 4770 (U2D1), pads 3046-3148 of 3647")
	)
	(layers
		(0 "F.Cu" signal "TOP")
		(4 "In1.Cu" signal "L2GND")
		(6 "In2.Cu" signal "L3")
		(8 "In3.Cu" signal "L4GND")
		(10 "In4.Cu" signal "L5")
		(12 "In5.Cu" signal "L6GND")
		(14 "In6.Cu" signal "L7VCC")
		(16 "In7.Cu" signal "L8VCC")
		(18 "In8.Cu" signal "L9GND")
		(20 "In9.Cu" signal "L10")
		(22 "In10.Cu" signal "L11GND")
		(24 "In11.Cu" signal "L12")
		(26 "In12.Cu" signal "L13GND")
		(2 "B.Cu" signal "BOTTOM")
		(9 "F.Adhes" user "F.Adhesive")
		(11 "B.Adhes" user "B.Adhesive")
		(13 "F.Paste" user "Package Geometry/Pastemask Top")
		(15 "B.Paste" user "Package Geometry/Pastemask Bottom")
		(5 "F.SilkS" user "Ref Des/Silkscreen Top")
		(7 "B.SilkS" user "Ref Des/Silkscreen Bottom")
		(1 "F.Mask" user "Board Geometry/Soldermask Top")
		(3 "B.Mask" user "Board Geometry/Soldermask Bottom")
		(17 "Dwgs.User" user "User.Drawings")
		(19 "Cmts.User" user "User.Comments")
		(21 "Eco1.User" user "User.Eco1")
		(23 "Eco2.User" user "User.Eco2")
		(25 "Edge.Cuts" user "Board Geometry/Outline")
		(27 "Margin" user)
		(31 "F.CrtYd" user "Package Geometry/Place Bound Top")
		(29 "B.CrtYd" user "Package Geometry/Place Bound Bottom")
		(35 "F.Fab" user "Ref Des/Assembly Top")
		(33 "B.Fab" user "Ref Des/Assembly Bottom")
	)
	(footprint ""
		(layer "F.Cu")
		(at 104.99979 -76.550012 180)
		(property "Reference" "U2D1"
			(at 25.19299 30.484318 0)
			(unlocked yes)
			(layer "F.SilkS")
			(effects
				(font
					(size 0.7874 0.5842)
					(thickness 0.1524)
				)
			)
		)
		(property "Value" ""
			(at 0 0 180)
			(layer "F.Fab")
			(effects
				(font
					(size 1.27 1.27)
				)
			)
		)
		(duplicate_pad_numbers_are_jumpers no)
		(pad "F69" smd custom
			(at 22.656038 -24.426672)
			(size 0.10795 0.10795)
			(layers "F.Cu" "F.Mask" "F.Paste")
			(net "GND")
			(options
				(clearance outline)
				(anchor circle)
			)
			(primitives
				(gr_poly
					(pts
						(arc
							(start 0.2159 -0.0381)
							(mid 0 -0.254)
							(end -0.2159 -0.0381)
						)
						(arc
							(start -0.2159 0.0381)
							(mid 0 0.254)
							(end 0.2159 0.0381)
						)
					)
					(width 0)
					(fill yes)
				)
			)
		)
		(pad "F71" smd custom
			(at 24.373078 -24.426672)
			(size 0.10795 0.10795)
			(layers "F.Cu" "F.Mask" "F.Paste")
			(net "M_H_DQ<27>")
			(options
				(clearance outline)
				(anchor circle)
			)
			(primitives
				(gr_poly
					(pts
						(arc
							(start 0.2159 -0.0381)
							(mid 0 -0.254)
							(end -0.2159 -0.0381)
						)
						(arc
							(start -0.2159 0.0381)
							(mid 0 0.254)
							(end 0.2159 0.0381)
						)
					)
					(width 0)
					(fill yes)
				)
			)
		)
		(pad "F73" smd circle
			(at 26.090118 -24.426672)
			(size 0.4318 0.4318)
			(layers "F.Cu" "F.Mask" "F.Paste")
			(net "M_H_DQS_DP<3>")
		)
		(pad "F75" smd circle
			(at 27.806904 -24.426672)
			(size 0.4318 0.4318)
			(layers "F.Cu" "F.Mask" "F.Paste")
			(net "M_H_DQ<28>")
		)
		(pad "F77" smd circle
			(at 29.523944 -24.426672)
			(size 0.4318 0.4318)
			(layers "F.Cu" "F.Mask" "F.Paste")
			(net "M_H_DQ<18>")
		)
		(pad "F79" smd circle
			(at 31.240984 -24.426672)
			(size 0.4318 0.4318)
			(layers "F.Cu" "F.Mask" "F.Paste")
			(net "M_H_DQS_DP<11>")
		)
		(pad "F81" smd circle
			(at 32.958024 -24.426672)
			(size 0.4318 0.4318)
			(layers "F.Cu" "F.Mask" "F.Paste")
			(net "M_H_DQ<20>")
		)
		(pad "F83" smd custom
			(at 34.675064 -24.426672 270)
			(size 0.10795 0.10795)
			(layers "F.Cu" "F.Mask" "F.Paste")
			(net "TP_CPU1_RSVD_276")
			(options
				(clearance outline)
				(anchor circle)
			)
			(primitives
				(gr_poly
					(pts
						(arc
							(start 0.2159 -0.0381)
							(mid 0 -0.254)
							(end -0.2159 -0.0381)
						)
						(arc
							(start -0.2159 0.0381)
							(mid 0 0.254)
							(end 0.2159 0.0381)
						)
					)
					(width 0)
					(fill yes)
				)
			)
		)
		(pad "G2" smd custom
			(at -36.392104 -22.131274 90)
			(size 0.10795 0.10795)
			(layers "F.Cu" "F.Mask" "F.Paste")
			(net "TP_CPU1_RSVD_275")
			(options
				(clearance outline)
				(anchor circle)
			)
			(primitives
				(gr_poly
					(pts
						(arc
							(start 0.2159 -0.0381)
							(mid 0 -0.254)
							(end -0.2159 -0.0381)
						)
						(arc
							(start -0.2159 0.0381)
							(mid 0 0.254)
							(end 0.2159 0.0381)
						)
					)
					(width 0)
					(fill yes)
				)
			)
		)
		(pad "G4" smd circle
			(at -34.675064 -22.131274)
			(size 0.4318 0.4318)
			(layers "F.Cu" "F.Mask" "F.Paste")
			(net "GND")
		)
		(pad "G6" smd circle
			(at -32.958024 -22.131274)
			(size 0.4318 0.4318)
			(layers "F.Cu" "F.Mask" "F.Paste")
			(net "UPI_CPU1_CPU0_P1P1_DN<4>")
		)
		(pad "G8" smd circle
			(at -31.240984 -22.131274)
			(size 0.4318 0.4318)
			(layers "F.Cu" "F.Mask" "F.Paste")
			(net "GND")
		)
		(pad "G10" smd circle
			(at -29.523944 -22.131274)
			(size 0.4318 0.4318)
			(layers "F.Cu" "F.Mask" "F.Paste")
			(net "UPI_CPU1_CPU0_P1P1_DN<9>")
		)
		(pad "G12" smd circle
			(at -27.806904 -22.131274)
			(size 0.4318 0.4318)
			(layers "F.Cu" "F.Mask" "F.Paste")
			(net "UPI_CPU1_CPU0_P1P1_DP<10>")
		)
		(pad "G14" smd circle
			(at -26.090118 -22.131274)
			(size 0.4318 0.4318)
			(layers "F.Cu" "F.Mask" "F.Paste")
			(net "UPI_CPU1_CPU0_P1P1_DP<11>")
		)
		(pad "G16" smd circle
			(at -24.373078 -22.131274)
			(size 0.4318 0.4318)
			(layers "F.Cu" "F.Mask" "F.Paste")
			(net "UPI_CPU1_CPU0_P1P1_DP<14>")
		)
		(pad "G18" smd circle
			(at -22.656038 -22.131274)
			(size 0.4318 0.4318)
			(layers "F.Cu" "F.Mask" "F.Paste")
			(net "UPI_CPU1_CPU0_P1P1_DN<16>")
		)
		(pad "G20" smd circle
			(at -20.938998 -22.131274)
			(size 0.4318 0.4318)
			(layers "F.Cu" "F.Mask" "F.Paste")
			(net "UPI_CPU1_CPU0_P1P1_DN<18>")
		)
		(pad "G22" smd circle
			(at -19.221958 -22.131274)
			(size 0.4318 0.4318)
			(layers "F.Cu" "F.Mask" "F.Paste")
			(net "GND")
		)
		(pad "G24" smd circle
			(at -17.504918 -22.131274)
			(size 0.4318 0.4318)
			(layers "F.Cu" "F.Mask" "F.Paste")
			(net "GND")
		)
		(pad "G26" smd circle
			(at -15.787878 -22.131274)
			(size 0.4318 0.4318)
			(layers "F.Cu" "F.Mask" "F.Paste")
			(net "GND")
		)
		(pad "G28" smd circle
			(at -14.071092 -22.131274)
			(size 0.4318 0.4318)
			(layers "F.Cu" "F.Mask" "F.Paste")
			(net "M_H_DQS_DN<6>")
		)
		(pad "G30" smd circle
			(at -12.354052 -22.131274)
			(size 0.4318 0.4318)
			(layers "F.Cu" "F.Mask" "F.Paste")
			(net "GND")
		)
		(pad "G32" smd circle
			(at -10.637012 -22.131274)
			(size 0.4318 0.4318)
			(layers "F.Cu" "F.Mask" "F.Paste")
			(net "GND")
		)
		(pad "G34" smd circle
			(at -8.919972 -22.131274)
			(size 0.4318 0.4318)
			(layers "F.Cu" "F.Mask" "F.Paste")
			(net "M_H_DQS_DN<5>")
		)
		(pad "G36" smd circle
			(at -7.202932 -22.131274)
			(size 0.4318 0.4318)
			(layers "F.Cu" "F.Mask" "F.Paste")
			(net "GND")
		)
		(pad "G38" smd circle
			(at -5.485892 -22.131274)
			(size 0.4318 0.4318)
			(layers "F.Cu" "F.Mask" "F.Paste")
			(net "GND")
		)
		(pad "G40" smd circle
			(at -3.769106 -22.131274)
			(size 0.4318 0.4318)
			(layers "F.Cu" "F.Mask" "F.Paste")
			(net "M_G_DQS_DN<4>")
		)
		(pad "G42" smd circle
			(at -2.052066 -22.131274)
			(size 0.4318 0.4318)
			(layers "F.Cu" "F.Mask" "F.Paste")
			(net "GND")
		)
		(pad "G46" smd circle
			(at 2.910586 -23.931626)
			(size 0.4318 0.4318)
			(layers "F.Cu" "F.Mask" "F.Paste")
			(net "M_G_C<2>")
		)
		(pad "G48" smd circle
			(at 4.627626 -23.931626)
			(size 0.4318 0.4318)
			(layers "F.Cu" "F.Mask" "F.Paste")
			(net "M_G_ODT<3>")
		)
		(pad "G50" smd circle
			(at 6.344412 -23.931626)
			(size 0.4318 0.4318)
			(layers "F.Cu" "F.Mask" "F.Paste")
			(net "M_G_ODT<2>")
		)
		(pad "G52" smd circle
			(at 8.061452 -23.931626)
			(size 0.4318 0.4318)
			(layers "F.Cu" "F.Mask" "F.Paste")
			(net "M_G_CS_N<0>")
		)
		(pad "G54" smd circle
			(at 9.778492 -23.931626)
			(size 0.4318 0.4318)
			(layers "F.Cu" "F.Mask" "F.Paste")
			(net "M_G_BA<1>")
		)
		(pad "G56" smd circle
			(at 11.495532 -23.931626)
			(size 0.4318 0.4318)
			(layers "F.Cu" "F.Mask" "F.Paste")
			(net "M_G_CLK_DP<2>")
		)
		(pad "G58" smd circle
			(at 13.212572 -23.931626)
			(size 0.4318 0.4318)
			(layers "F.Cu" "F.Mask" "F.Paste")
			(net "M_G_MA<4>")
		)
		(pad "G60" smd circle
			(at 14.929612 -23.931626)
			(size 0.4318 0.4318)
			(layers "F.Cu" "F.Mask" "F.Paste")
			(net "M_G_MA<7>")
		)
		(pad "G62" smd circle
			(at 16.646398 -23.931626)
			(size 0.4318 0.4318)
			(layers "F.Cu" "F.Mask" "F.Paste")
			(net "M_G_MA<11>")
		)
		(pad "G64" smd circle
			(at 18.363438 -23.931626)
			(size 0.4318 0.4318)
			(layers "F.Cu" "F.Mask" "F.Paste")
			(net "TP_CPU1_RSVD_274")
		)
		(pad "G66" smd circle
			(at 20.080478 -23.931626)
			(size 0.4318 0.4318)
			(layers "F.Cu" "F.Mask" "F.Paste")
			(net "GND")
		)
		(pad "G68" smd circle
			(at 21.797518 -23.931626)
			(size 0.4318 0.4318)
			(layers "F.Cu" "F.Mask" "F.Paste")
			(net "M_H_DQS_DN<17>")
		)
		(pad "G70" smd circle
			(at 23.514558 -23.931626)
			(size 0.4318 0.4318)
			(layers "F.Cu" "F.Mask" "F.Paste")
			(net "GND")
		)
		(pad "G72" smd circle
			(at 25.231598 -23.931626)
			(size 0.4318 0.4318)
			(layers "F.Cu" "F.Mask" "F.Paste")
			(net "M_H_DQ<31>")
		)
		(pad "G74" smd circle
			(at 26.948384 -23.931626)
			(size 0.4318 0.4318)
			(layers "F.Cu" "F.Mask" "F.Paste")
			(net "M_H_DQ<29>")
		)
		(pad "G76" smd circle
			(at 28.665424 -23.931626)
			(size 0.4318 0.4318)
			(layers "F.Cu" "F.Mask" "F.Paste")
			(net "GND")
		)
		(pad "G78" smd circle
			(at 30.382464 -23.931626)
			(size 0.4318 0.4318)
			(layers "F.Cu" "F.Mask" "F.Paste")
			(net "GND")
		)
		(pad "G80" smd circle
			(at 32.099504 -23.931626)
			(size 0.4318 0.4318)
			(layers "F.Cu" "F.Mask" "F.Paste")
			(net "GND")
		)
		(pad "G82" smd circle
			(at 33.816544 -23.931626)
			(size 0.4318 0.4318)
			(layers "F.Cu" "F.Mask" "F.Paste")
			(net "GND")
		)
		(pad "G84" smd custom
			(at 35.533584 -23.931626 270)
			(size 0.10795 0.10795)
			(layers "F.Cu" "F.Mask" "F.Paste")
			(net "TP_CPU1_RSVD_273")
			(options
				(clearance outline)
				(anchor circle)
			)
			(primitives
				(gr_poly
					(pts
						(arc
							(start 0.2159 -0.0381)
							(mid 0 -0.254)
							(end -0.2159 -0.0381)
						)
						(arc
							(start -0.2159 0.0381)
							(mid 0 0.254)
							(end 0.2159 0.0381)
						)
					)
					(width 0)
					(fill yes)
				)
			)
		)
		(pad "H1" smd custom
			(at -37.250624 -21.636228 90)
			(size 0.10795 0.10795)
			(layers "F.Cu" "F.Mask" "F.Paste")
			(net "TP_CPU1_RSVD_272")
			(options
				(clearance outline)
				(anchor circle)
			)
			(primitives
				(gr_poly
					(pts
						(arc
							(start 0.2159 -0.0381)
							(mid 0 -0.254)
							(end -0.2159 -0.0381)
						)
						(arc
							(start -0.2159 0.0381)
							(mid 0 0.254)
							(end 0.2159 0.0381)
						)
					)
					(width 0)
					(fill yes)
				)
			)
		)
		(pad "H3" smd circle
			(at -35.533584 -21.636228)
			(size 0.4318 0.4318)
			(layers "F.Cu" "F.Mask" "F.Paste")
			(net "GND")
		)
		(pad "H5" smd circle
			(at -33.816544 -21.636228)
			(size 0.4318 0.4318)
			(layers "F.Cu" "F.Mask" "F.Paste")
			(net "UPI_CPU1_CPU0_P1P1_DP<3>")
		)
		(pad "H7" smd circle
			(at -32.099504 -21.636228)
			(size 0.4318 0.4318)
			(layers "F.Cu" "F.Mask" "F.Paste")
			(net "UPI_CPU1_CPU0_P1P1_DN<5>")
		)
		(pad "H9" smd circle
			(at -30.382464 -21.636228)
			(size 0.4318 0.4318)
			(layers "F.Cu" "F.Mask" "F.Paste")
			(net "UPI_CPU1_CPU0_P1P1_DP<9>")
		)
		(pad "H11" smd circle
			(at -28.665424 -21.636228)
			(size 0.4318 0.4318)
			(layers "F.Cu" "F.Mask" "F.Paste")
			(net "GND")
		)
		(pad "H13" smd circle
			(at -26.948384 -21.636228)
			(size 0.4318 0.4318)
			(layers "F.Cu" "F.Mask" "F.Paste")
			(net "PVCCIO_CPU1")
		)
		(pad "H15" smd circle
			(at -25.231598 -21.636228)
			(size 0.4318 0.4318)
			(layers "F.Cu" "F.Mask" "F.Paste")
			(net "UPI_CPU1_CPU0_P1P1_DP<13>")
		)
		(pad "H17" smd circle
			(at -23.514558 -21.636228)
			(size 0.4318 0.4318)
			(layers "F.Cu" "F.Mask" "F.Paste")
			(net "UPI_CPU1_CPU0_P1P1_DN<14>")
		)
		(pad "H19" smd circle
			(at -21.797518 -21.636228)
			(size 0.4318 0.4318)
			(layers "F.Cu" "F.Mask" "F.Paste")
			(net "UPI_CPU1_CPU0_P1P1_DP<17>")
		)
		(pad "H21" smd circle
			(at -20.080478 -21.636228)
			(size 0.4318 0.4318)
			(layers "F.Cu" "F.Mask" "F.Paste")
			(net "UPI_CPU1_CPU0_P1P1_DP<19>")
		)
		(pad "H23" smd circle
			(at -18.363438 -21.636228)
			(size 0.4318 0.4318)
			(layers "F.Cu" "F.Mask" "F.Paste")
			(net "M_G_DQ<62>")
		)
		(pad "H25" smd circle
			(at -16.646398 -21.636228)
			(size 0.4318 0.4318)
			(layers "F.Cu" "F.Mask" "F.Paste")
			(net "GND")
		)
		(pad "H27" smd circle
			(at -14.929612 -21.636228)
			(size 0.4318 0.4318)
			(layers "F.Cu" "F.Mask" "F.Paste")
			(net "GND")
		)
		(pad "H29" smd circle
			(at -13.212572 -21.636228)
			(size 0.4318 0.4318)
			(layers "F.Cu" "F.Mask" "F.Paste")
			(net "GND")
		)
		(pad "H31" smd circle
			(at -11.495532 -21.636228)
			(size 0.4318 0.4318)
			(layers "F.Cu" "F.Mask" "F.Paste")
			(net "GND")
		)
		(pad "H33" smd circle
			(at -9.778492 -21.636228)
			(size 0.4318 0.4318)
			(layers "F.Cu" "F.Mask" "F.Paste")
			(net "GND")
		)
		(pad "H35" smd circle
			(at -8.061452 -21.636228)
			(size 0.4318 0.4318)
			(layers "F.Cu" "F.Mask" "F.Paste")
			(net "GND")
		)
		(pad "H37" smd circle
			(at -6.344412 -21.636228)
			(size 0.4318 0.4318)
			(layers "F.Cu" "F.Mask" "F.Paste")
			(net "GND")
		)
		(pad "H39" smd circle
			(at -4.627626 -21.636228)
			(size 0.4318 0.4318)
			(layers "F.Cu" "F.Mask" "F.Paste")
			(net "GND")
		)
		(pad "H41" smd circle
			(at -2.910586 -21.636228)
			(size 0.4318 0.4318)
			(layers "F.Cu" "F.Mask" "F.Paste")
			(net "GND")
		)
		(pad "H43" smd circle
			(at -1.193546 -21.636228)
			(size 0.4318 0.4318)
			(layers "F.Cu" "F.Mask" "F.Paste")
			(net "M_H_DQ<33>")
		)
		(pad "H45" smd circle
			(at 2.052066 -23.436326)
			(size 0.508 0.508)
			(layers "F.Cu" "F.Mask" "F.Paste")
			(net "GND")
		)
		(pad "H47" smd circle
			(at 3.769106 -23.436326)
			(size 0.4318 0.4318)
			(layers "F.Cu" "F.Mask" "F.Paste")
			(net "GND")
		)
		(pad "H49" smd circle
			(at 5.485892 -23.436326)
			(size 0.4318 0.4318)
			(layers "F.Cu" "F.Mask" "F.Paste")
			(net "GND")
		)
		(pad "H51" smd circle
			(at 7.202932 -23.436326)
			(size 0.4318 0.4318)
			(layers "F.Cu" "F.Mask" "F.Paste")
			(net "GND")
		)
		(pad "H53" smd circle
			(at 8.919972 -23.436326)
			(size 0.4318 0.4318)
			(layers "F.Cu" "F.Mask" "F.Paste")
			(net "GND")
		)
		(pad "H55" smd circle
			(at 10.637012 -23.436326)
			(size 0.4318 0.4318)
			(layers "F.Cu" "F.Mask" "F.Paste")
			(net "GND")
		)
		(pad "H57" smd circle
			(at 12.354052 -23.436326)
			(size 0.4318 0.4318)
			(layers "F.Cu" "F.Mask" "F.Paste")
			(net "GND")
		)
		(pad "H59" smd circle
			(at 14.071092 -23.436326)
			(size 0.4318 0.4318)
			(layers "F.Cu" "F.Mask" "F.Paste")
			(net "GND")
		)
		(pad "H61" smd circle
			(at 15.787878 -23.436326)
			(size 0.4318 0.4318)
			(layers "F.Cu" "F.Mask" "F.Paste")
			(net "GND")
		)
		(pad "H63" smd circle
			(at 17.504918 -23.436326)
			(size 0.4318 0.4318)
			(layers "F.Cu" "F.Mask" "F.Paste")
			(net "GND")
		)
		(pad "H65" smd circle
			(at 19.221958 -23.436326)
			(size 0.4318 0.4318)
			(layers "F.Cu" "F.Mask" "F.Paste")
			(net "GND")
		)
		(pad "H67" smd circle
			(at 20.938998 -23.436326)
			(size 0.4318 0.4318)
			(layers "F.Cu" "F.Mask" "F.Paste")
			(net "M_H_ECC<6>")
		)
		(pad "H69" smd circle
			(at 22.656038 -23.436326)
			(size 0.4318 0.4318)
			(layers "F.Cu" "F.Mask" "F.Paste")
			(net "M_H_ECC<1>")
		)
		(pad "H71" smd circle
			(at 24.373078 -23.436326)
			(size 0.4318 0.4318)
			(layers "F.Cu" "F.Mask" "F.Paste")
			(net "GND")
		)
		(pad "H73" smd circle
			(at 26.090118 -23.436326)
			(size 0.4318 0.4318)
			(layers "F.Cu" "F.Mask" "F.Paste")
			(net "M_H_DQS_DN<3>")
		)
		(pad "H75" smd circle
			(at 27.806904 -23.436326)
			(size 0.4318 0.4318)
			(layers "F.Cu" "F.Mask" "F.Paste")
			(net "GND")
		)
		(pad "H77" smd circle
			(at 29.523944 -23.436326)
			(size 0.4318 0.4318)
			(layers "F.Cu" "F.Mask" "F.Paste")
			(net "M_H_DQ<19>")
		)
		(pad "H79" smd circle
			(at 31.240984 -23.436326)
			(size 0.4318 0.4318)
			(layers "F.Cu" "F.Mask" "F.Paste")
			(net "M_H_DQS_DP<2>")
		)
		(pad "H81" smd circle
			(at 32.958024 -23.436326)
			(size 0.4318 0.4318)
			(layers "F.Cu" "F.Mask" "F.Paste")
			(net "M_H_DQ<21>")
		)
		(pad "H83" smd circle
			(at 34.675064 -23.436326)
			(size 0.4318 0.4318)
			(layers "F.Cu" "F.Mask" "F.Paste")
			(net "TP_CPU1_RSVD_271")
		)
		(pad "H85" smd custom
			(at 36.392104 -23.436326 270)
			(size 0.10795 0.10795)
			(layers "F.Cu" "F.Mask" "F.Paste")
			(net "TP_CPU1_RSVD_270")
			(options
				(clearance outline)
				(anchor circle)
			)
			(primitives
				(gr_poly
					(pts
						(arc
							(start 0.2159 -0.0381)
							(mid 0 -0.254)
							(end -0.2159 -0.0381)
						)
						(arc
							(start -0.2159 0.0381)
							(mid 0 0.254)
							(end 0.2159 0.0381)
						)
					)
					(width 0)
					(fill yes)
				)
			)
		)
		(pad "J2" smd circle
			(at -36.392104 -21.140674)
			(size 0.4318 0.4318)
			(layers "F.Cu" "F.Mask" "F.Paste")
			(net "PVCCIO_CPU1")
		)
		(pad "J4" smd circle
			(at -34.675064 -21.140674)
			(size 0.4318 0.4318)
			(layers "F.Cu" "F.Mask" "F.Paste")
			(net "GND")
		)
		(pad "J6" smd circle
			(at -32.958024 -21.140674)
			(size 0.4318 0.4318)
			(layers "F.Cu" "F.Mask" "F.Paste")
			(net "UPI_CPU1_CPU0_P1P1_DN<3>")
		)
		(pad "J8" smd circle
			(at -31.240984 -21.140674)
			(size 0.4318 0.4318)
			(layers "F.Cu" "F.Mask" "F.Paste")
			(net "UPI_CPU1_CPU0_P1P1_DN<6>")
		)
		(pad "J10" smd circle
			(at -29.523944 -21.140674)
			(size 0.4318 0.4318)
			(layers "F.Cu" "F.Mask" "F.Paste")
			(net "PVCCIO_CPU1")
		)
		(pad "J12" smd circle
			(at -27.806904 -21.140674)
			(size 0.4318 0.4318)
			(layers "F.Cu" "F.Mask" "F.Paste")
			(net "GND")
		)
		(pad "J14" smd circle
			(at -26.090118 -21.140674)
			(size 0.4318 0.4318)
			(layers "F.Cu" "F.Mask" "F.Paste")
			(net "GND")
		)
		(pad "J16" smd circle
			(at -24.373078 -21.140674)
			(size 0.4318 0.4318)
			(layers "F.Cu" "F.Mask" "F.Paste")
			(net "GND")
		)
		(pad "J18" smd circle
			(at -22.656038 -21.140674)
			(size 0.4318 0.4318)
			(layers "F.Cu" "F.Mask" "F.Paste")
			(net "UPI_CPU1_CPU0_P1P1_DP<16>")
		)
		(pad "J20" smd circle
			(at -20.938998 -21.140674)
			(size 0.4318 0.4318)
			(layers "F.Cu" "F.Mask" "F.Paste")
			(net "UPI_CPU1_CPU0_P1P1_DN<17>")
		)
		(pad "J22" smd circle
			(at -19.221958 -21.140674)
			(size 0.4318 0.4318)
			(layers "F.Cu" "F.Mask" "F.Paste")
			(net "GND")
		)
	)
)
